#ISCELL
  logical_power bom_note *
  *
#ISCELL
  logical_power cad_note *
  *
#ISCELL
  mstr_misc dns *
  *
#ISCELL
  pure_quanta quanta_title_block_c *
  *
#ISCELL
  logical_power universal_gnd *
  page171_i1
#CELL
  pure_quanta q_cap *
  page171_i10
#ISCELL
  standard offpage *
  page171_i100
#CELL
  pure_quanta q_res *
  page171_i103
#CELL
  pure_quanta q_res *
  page171_i104
#ISCELL
  standard offpage *
  page171_i107
#ISCELL
  standard offpage *
  page171_i108
#ISCELL
  standard offpage *
  page171_i109
#CELL
  pure_quanta q_crystal *
  page171_i11
#ISCELL
  standard offpage *
  page171_i110
#ISCELL
  standard offpage *
  page171_i111
#ISCELL
  standard offpage *
  page171_i112
#ISCELL
  standard offpage *
  page171_i114
#CELL
  pure_quanta q_res *
  page171_i116
#CELL
  pure_quanta q_res *
  page171_i117
#ISCELL
  standard offpage *
  page171_i118
#ISCELL
  standard offpage *
  page171_i119
#ISCELL
  standard offpage *
  page171_i120
#CELL
  pure_quanta q_res *
  page171_i121
#CELL
  pure_quanta q_res *
  page171_i122
#ISCELL
  standard offpage *
  page171_i14
#ISCELL
  standard offpage *
  page171_i15
#ISCELL
  logical_power universal_gnd *
  page171_i16
#CELL
  pure_quanta q_cap *
  page171_i17
#ISCELL
  standard offpage *
  page171_i18
#ISCELL
  standard offpage *
  page171_i19
#ISCELL
  logical_power universal_gnd *
  page171_i5
#ISCELL
  standard offpage *
  page171_i63
#ISCELL
  standard offpage *
  page171_i64
#ISCELL
  standard offpage *
  page171_i66
#ISCELL
  standard offpage *
  page171_i67
#ISCELL
  standard offpage *
  page171_i68
#CELL
  pure_quanta q_res *
  page171_i69
#ISCELL
  logical_power universal_gnd *
  page171_i7
#CELL
  pure_quanta q_res *
  page171_i74
#CELL
  pure_quanta q_xtal_4p_13bi_24gnd *
  page171_i75
#CELL
  pure_quanta q_cap *
  page171_i76
#CELL
  pure_quanta q_cap *
  page171_i77
#CELL
  pure_quanta emmitsburg_rev0p9 *
  page171_i78
#ISCELL
  standard offpage *
  page171_i83
#ISCELL
  standard offpage *
  page171_i84
#ISCELL
  standard offpage *
  page171_i85
#ISCELL
  standard offpage *
  page171_i86
#ISCELL
  standard offpage *
  page171_i87
#ISCELL
  standard offpage *
  page171_i88
#CELL
  pure_quanta q_cap *
  page171_i89
#ISCELL
  logical_power universal_gnd *
  page171_i9
#ISCELL
  logical_power universal_gnd *
  page171_i90
#ISCELL
  standard offpage *
  page171_i91
#CELL
  pure_quanta q_res *
  page171_i92
#ISCELL
  standard offpage *
  page171_i97
#ISCELL
  standard offpage *
  page171_i98
#ISCELL
  standard offpage *
  page171_i99
